(kicad_pcb
	(version 20260206)
	(generator "pcbnew")
	(generator_version "10.0")
	(general
		(thickness 1.6)
		(legacy_teardrops no)
	)
	(paper "A4")
	(title_block
		(title "01162023_DA0F0TEBIF0_F0T_Expander_BD_F_brd_V02_OCP.brd")
		(comment 1 "Grand Teton / footprints 3385-3391 of 9728")
	)
	(layers
		(0 "F.Cu" signal "TOP")
		(4 "In1.Cu" signal "GND")
		(6 "In2.Cu" signal "VCC")
		(8 "In3.Cu" signal "VCC1")
		(10 "In4.Cu" signal "GND1")
		(12 "In5.Cu" signal "IN1")
		(14 "In6.Cu" signal "GND2")
		(16 "In7.Cu" signal "IN2")
		(18 "In8.Cu" signal "GND3")
		(20 "In9.Cu" signal "IN3")
		(22 "In10.Cu" signal "GND4")
		(24 "In11.Cu" signal "IN4")
		(26 "In12.Cu" signal "GND5")
		(28 "In13.Cu" signal "IN5")
		(30 "In14.Cu" signal "GND6")
		(32 "In15.Cu" signal "IN6")
		(34 "In16.Cu" signal "GND7")
		(2 "B.Cu" signal "BOTTOM")
		(9 "F.Adhes" user "F.Adhesive")
		(11 "B.Adhes" user "B.Adhesive")
		(13 "F.Paste" user "Package Geometry/Pastemask Top")
		(15 "B.Paste" user "Package Geometry/Pastemask Bottom")
		(5 "F.SilkS" user "Ref Des/Silkscreen Top")
		(7 "B.SilkS" user "Ref Des/Silkscreen Bottom")
		(1 "F.Mask" user "Board Geometry/Soldermask Top")
		(3 "B.Mask" user "Board Geometry/Soldermask Bottom")
		(17 "Dwgs.User" user "User.Drawings")
		(19 "Cmts.User" user "User.Comments")
		(21 "Eco1.User" user "User.Eco1")
		(23 "Eco2.User" user "User.Eco2")
		(25 "Edge.Cuts" user "Board Geometry/Outline")
		(27 "Margin" user)
		(31 "F.CrtYd" user "Package Geometry/Place Bound Top")
		(29 "B.CrtYd" user "Package Geometry/Place Bound Bottom")
		(35 "F.Fab" user "Ref Des/Assembly Top")
		(33 "B.Fab" user "Ref Des/Assembly Bottom")
	)
	(footprint ""
		(layer "F.Cu")
		(at 208.999074 -212.913214 90)
		(property "Reference" "C2570"
			(at 0 0 90)
			(layer "F.SilkS")
			(hide yes)
			(effects
				(font
					(size 1.27 1.27)
				)
			)
		)
		(property "Value" ""
			(at 0 0 90)
			(layer "F.Fab")
			(effects
				(font
					(size 1.27 1.27)
				)
			)
		)
		(duplicate_pad_numbers_are_jumpers no)
		(fp_line
			(start 0.7874 -0.4064)
			(end 0.7874 0.4064)
			(stroke
				(width 0.1524)
				(type default)
			)
			(layer "F.SilkS")
		)
		(fp_line
			(start -0.7874 -0.4064)
			(end 0.7874 -0.4064)
			(stroke
				(width 0.1524)
				(type default)
			)
			(layer "F.SilkS")
		)
		(fp_line
			(start 0.7874 0.4064)
			(end -0.7874 0.4064)
			(stroke
				(width 0.1524)
				(type default)
			)
			(layer "F.SilkS")
		)
		(fp_line
			(start -0.7874 0.4064)
			(end -0.7874 -0.4064)
			(stroke
				(width 0.1524)
				(type default)
			)
			(layer "F.SilkS")
		)
		(fp_line
			(start -0.12065 -0.305054)
			(end -0.12065 -0.2794)
			(stroke
				(width 0.1)
				(type default)
			)
			(layer "F.Fab")
		)
		(fp_line
			(start -0.67945 -0.305054)
			(end -0.12065 -0.305054)
			(stroke
				(width 0.1)
				(type default)
			)
			(layer "F.Fab")
		)
		(fp_line
			(start 0.67945 -0.3048)
			(end 0.67945 0.3048)
			(stroke
				(width 0.1)
				(type default)
			)
			(layer "F.Fab")
		)
		(fp_line
			(start 0.12065 -0.3048)
			(end 0.67945 -0.3048)
			(stroke
				(width 0.1)
				(type default)
			)
			(layer "F.Fab")
		)
		(fp_line
			(start 0.12065 -0.2794)
			(end 0.12065 -0.3048)
			(stroke
				(width 0.1)
				(type default)
			)
			(layer "F.Fab")
		)
		(fp_line
			(start -0.12065 -0.2794)
			(end 0.12065 -0.2794)
			(stroke
				(width 0.1)
				(type default)
			)
			(layer "F.Fab")
		)
		(fp_line
			(start 0.120396 0.2794)
			(end -0.12065 0.2794)
			(stroke
				(width 0.1)
				(type default)
			)
			(layer "F.Fab")
		)
		(fp_line
			(start -0.12065 0.2794)
			(end -0.12065 0.3048)
			(stroke
				(width 0.1)
				(type default)
			)
			(layer "F.Fab")
		)
		(fp_line
			(start 0.67945 0.3048)
			(end 0.120396 0.3048)
			(stroke
				(width 0.1)
				(type default)
			)
			(layer "F.Fab")
		)
		(fp_line
			(start 0.120396 0.3048)
			(end 0.120396 0.2794)
			(stroke
				(width 0.1)
				(type default)
			)
			(layer "F.Fab")
		)
		(fp_line
			(start -0.12065 0.3048)
			(end -0.67945 0.3048)
			(stroke
				(width 0.1)
				(type default)
			)
			(layer "F.Fab")
		)
		(fp_line
			(start -0.67945 0.3048)
			(end -0.67945 -0.305054)
			(stroke
				(width 0.1)
				(type default)
			)
			(layer "F.Fab")
		)
		(pad "1" smd circle
			(at -0.40005 0 90)
			(size 0 0)
			(layers "F.Cu" "F.Mask" "F.Paste")
			(net "GND")
		)
		(pad "2" smd circle
			(at 0.40005 0 90)
			(size 0 0)
			(layers "F.Cu" "F.Mask" "F.Paste")
			(net "P3V3_AUX")
		)
	)
	(footprint ""
		(layer "F.Cu")
		(at 256.583434 -49.94148 180)
		(property "Reference" "R600"
			(at 0 0 180)
			(layer "F.SilkS")
			(hide yes)
			(effects
				(font
					(size 1.27 1.27)
				)
			)
		)
		(property "Value" ""
			(at 0 0 180)
			(layer "F.Fab")
			(effects
				(font
					(size 1.27 1.27)
				)
			)
		)
		(duplicate_pad_numbers_are_jumpers no)
		(fp_line
			(start 0.7874 0.4064)
			(end -0.7874 0.4064)
			(stroke
				(width 0.1524)
				(type default)
			)
			(layer "F.SilkS")
		)
		(fp_line
			(start 0.7874 -0.4064)
			(end 0.7874 0.4064)
			(stroke
				(width 0.1524)
				(type default)
			)
			(layer "F.SilkS")
		)
		(fp_line
			(start -0.7874 0.4064)
			(end -0.7874 -0.4064)
			(stroke
				(width 0.1524)
				(type default)
			)
			(layer "F.SilkS")
		)
		(fp_line
			(start -0.7874 -0.4064)
			(end 0.7874 -0.4064)
			(stroke
				(width 0.1524)
				(type default)
			)
			(layer "F.SilkS")
		)
		(fp_line
			(start 0.67945 0.3048)
			(end 0.120396 0.3048)
			(stroke
				(width 0.1)
				(type default)
			)
			(layer "F.Fab")
		)
		(fp_line
			(start 0.67945 -0.3048)
			(end 0.67945 0.3048)
			(stroke
				(width 0.1)
				(type default)
			)
			(layer "F.Fab")
		)
		(fp_line
			(start 0.12065 -0.2794)
			(end 0.12065 -0.3048)
			(stroke
				(width 0.1)
				(type default)
			)
			(layer "F.Fab")
		)
		(fp_line
			(start 0.12065 -0.3048)
			(end 0.67945 -0.3048)
			(stroke
				(width 0.1)
				(type default)
			)
			(layer "F.Fab")
		)
		(fp_line
			(start 0.120396 0.3048)
			(end 0.120396 0.2794)
			(stroke
				(width 0.1)
				(type default)
			)
			(layer "F.Fab")
		)
		(fp_line
			(start 0.120396 0.2794)
			(end -0.12065 0.2794)
			(stroke
				(width 0.1)
				(type default)
			)
			(layer "F.Fab")
		)
		(fp_line
			(start -0.12065 0.3048)
			(end -0.67945 0.3048)
			(stroke
				(width 0.1)
				(type default)
			)
			(layer "F.Fab")
		)
		(fp_line
			(start -0.12065 0.2794)
			(end -0.12065 0.3048)
			(stroke
				(width 0.1)
				(type default)
			)
			(layer "F.Fab")
		)
		(fp_line
			(start -0.12065 -0.2794)
			(end 0.12065 -0.2794)
			(stroke
				(width 0.1)
				(type default)
			)
			(layer "F.Fab")
		)
		(fp_line
			(start -0.12065 -0.305054)
			(end -0.12065 -0.2794)
			(stroke
				(width 0.1)
				(type default)
			)
			(layer "F.Fab")
		)
		(fp_line
			(start -0.67945 0.3048)
			(end -0.67945 -0.305054)
			(stroke
				(width 0.1)
				(type default)
			)
			(layer "F.Fab")
		)
		(fp_line
			(start -0.67945 -0.305054)
			(end -0.12065 -0.305054)
			(stroke
				(width 0.1)
				(type default)
			)
			(layer "F.Fab")
		)
		(pad "1" smd circle
			(at -0.40005 0 180)
			(size 0 0)
			(layers "F.Cu" "F.Mask" "F.Paste")
			(net "SMB_BIC_I2C6_MUX_SSD_8_15_ADC_R_SDA")
		)
		(pad "2" smd circle
			(at 0.40005 0 180)
			(size 0 0)
			(layers "F.Cu" "F.Mask" "F.Paste")
			(net "SMB_SSD8_ADC_SDA")
		)
	)
	(footprint ""
		(layer "F.Cu")
		(at 360.147362 -112.755426 90)
		(property "Reference" "R6048"
			(at 0 0 90)
			(layer "F.SilkS")
			(hide yes)
			(effects
				(font
					(size 1.27 1.27)
				)
			)
		)
		(property "Value" ""
			(at 0 0 90)
			(layer "F.Fab")
			(effects
				(font
					(size 1.27 1.27)
				)
			)
		)
		(duplicate_pad_numbers_are_jumpers no)
		(fp_line
			(start 0.7874 -0.4064)
			(end 0.7874 0.4064)
			(stroke
				(width 0.1524)
				(type default)
			)
			(layer "F.SilkS")
		)
		(fp_line
			(start -0.7874 -0.4064)
			(end 0.7874 -0.4064)
			(stroke
				(width 0.1524)
				(type default)
			)
			(layer "F.SilkS")
		)
		(fp_line
			(start 0.7874 0.4064)
			(end -0.7874 0.4064)
			(stroke
				(width 0.1524)
				(type default)
			)
			(layer "F.SilkS")
		)
		(fp_line
			(start -0.7874 0.4064)
			(end -0.7874 -0.4064)
			(stroke
				(width 0.1524)
				(type default)
			)
			(layer "F.SilkS")
		)
		(fp_line
			(start -0.12065 -0.305054)
			(end -0.12065 -0.2794)
			(stroke
				(width 0.1)
				(type default)
			)
			(layer "F.Fab")
		)
		(fp_line
			(start -0.67945 -0.305054)
			(end -0.12065 -0.305054)
			(stroke
				(width 0.1)
				(type default)
			)
			(layer "F.Fab")
		)
		(fp_line
			(start 0.67945 -0.3048)
			(end 0.67945 0.3048)
			(stroke
				(width 0.1)
				(type default)
			)
			(layer "F.Fab")
		)
		(fp_line
			(start 0.12065 -0.3048)
			(end 0.67945 -0.3048)
			(stroke
				(width 0.1)
				(type default)
			)
			(layer "F.Fab")
		)
		(fp_line
			(start 0.12065 -0.2794)
			(end 0.12065 -0.3048)
			(stroke
				(width 0.1)
				(type default)
			)
			(layer "F.Fab")
		)
		(fp_line
			(start -0.12065 -0.2794)
			(end 0.12065 -0.2794)
			(stroke
				(width 0.1)
				(type default)
			)
			(layer "F.Fab")
		)
		(fp_line
			(start 0.120396 0.2794)
			(end -0.12065 0.2794)
			(stroke
				(width 0.1)
				(type default)
			)
			(layer "F.Fab")
		)
		(fp_line
			(start -0.12065 0.2794)
			(end -0.12065 0.3048)
			(stroke
				(width 0.1)
				(type default)
			)
			(layer "F.Fab")
		)
		(fp_line
			(start 0.67945 0.3048)
			(end 0.120396 0.3048)
			(stroke
				(width 0.1)
				(type default)
			)
			(layer "F.Fab")
		)
		(fp_line
			(start 0.120396 0.3048)
			(end 0.120396 0.2794)
			(stroke
				(width 0.1)
				(type default)
			)
			(layer "F.Fab")
		)
		(fp_line
			(start -0.12065 0.3048)
			(end -0.67945 0.3048)
			(stroke
				(width 0.1)
				(type default)
			)
			(layer "F.Fab")
		)
		(fp_line
			(start -0.67945 0.3048)
			(end -0.67945 -0.305054)
			(stroke
				(width 0.1)
				(type default)
			)
			(layer "F.Fab")
		)
		(pad "1" smd circle
			(at -0.40005 0 90)
			(size 0 0)
			(layers "F.Cu" "F.Mask" "F.Paste")
			(net "P5V_AUX")
		)
		(pad "2" smd circle
			(at 0.40005 0 90)
			(size 0 0)
			(layers "F.Cu" "F.Mask" "F.Paste")
			(net "P3V3_NIC6_PG_G2")
		)
	)
	(footprint ""
		(layer "F.Cu")
		(at 336.838544 -80.607662 90)
		(property "Reference" "R1172"
			(at 0 0 90)
			(layer "F.SilkS")
			(hide yes)
			(effects
				(font
					(size 1.27 1.27)
				)
			)
		)
		(property "Value" ""
			(at 0 0 90)
			(layer "F.Fab")
			(effects
				(font
					(size 1.27 1.27)
				)
			)
		)
		(duplicate_pad_numbers_are_jumpers no)
		(fp_line
			(start -0.7874 -0.4064)
			(end 0.7874 -0.4064)
			(stroke
				(width 0.1524)
				(type default)
			)
			(layer "F.SilkS")
		)
		(fp_line
			(start -0.12065 -0.305054)
			(end -0.12065 -0.2794)
			(stroke
				(width 0.1)
				(type default)
			)
			(layer "F.Fab")
		)
		(fp_line
			(start -0.67945 -0.305054)
			(end -0.12065 -0.305054)
			(stroke
				(width 0.1)
				(type default)
			)
			(layer "F.Fab")
		)
		(fp_line
			(start 0.67945 -0.3048)
			(end 0.67945 0.3048)
			(stroke
				(width 0.1)
				(type default)
			)
			(layer "F.Fab")
		)
		(fp_line
			(start 0.12065 -0.3048)
			(end 0.67945 -0.3048)
			(stroke
				(width 0.1)
				(type default)
			)
			(layer "F.Fab")
		)
		(fp_line
			(start 0.12065 -0.2794)
			(end 0.12065 -0.3048)
			(stroke
				(width 0.1)
				(type default)
			)
			(layer "F.Fab")
		)
		(fp_line
			(start -0.12065 -0.2794)
			(end 0.12065 -0.2794)
			(stroke
				(width 0.1)
				(type default)
			)
			(layer "F.Fab")
		)
		(fp_line
			(start 0.120396 0.2794)
			(end -0.12065 0.2794)
			(stroke
				(width 0.1)
				(type default)
			)
			(layer "F.Fab")
		)
		(fp_line
			(start -0.12065 0.2794)
			(end -0.12065 0.3048)
			(stroke
				(width 0.1)
				(type default)
			)
			(layer "F.Fab")
		)
		(fp_line
			(start 0.67945 0.3048)
			(end 0.120396 0.3048)
			(stroke
				(width 0.1)
				(type default)
			)
			(layer "F.Fab")
		)
		(fp_line
			(start 0.120396 0.3048)
			(end 0.120396 0.2794)
			(stroke
				(width 0.1)
				(type default)
			)
			(layer "F.Fab")
		)
		(fp_line
			(start -0.12065 0.3048)
			(end -0.67945 0.3048)
			(stroke
				(width 0.1)
				(type default)
			)
			(layer "F.Fab")
		)
		(fp_line
			(start -0.67945 0.3048)
			(end -0.67945 -0.305054)
			(stroke
				(width 0.1)
				(type default)
			)
			(layer "F.Fab")
		)
		(pad "1" smd circle
			(at -0.40005 0 90)
			(size 0 0)
			(layers "F.Cu" "F.Mask" "F.Paste")
			(net "CLK_100M_DB800ZL_SSD9_R_DP")
		)
		(pad "2" smd circle
			(at 0.40005 0 90)
			(size 0 0)
			(layers "F.Cu" "F.Mask" "F.Paste")
			(net "CLK_100M_DB800ZL_SSD9_DP")
		)
	)
	(footprint ""
		(layer "F.Cu")
		(at 337.582256 -93.154246 90)
		(property "Reference" "R3512"
			(at 0 0 90)
			(layer "F.SilkS")
			(hide yes)
			(effects
				(font
					(size 1.27 1.27)
				)
			)
		)
		(property "Value" ""
			(at 0 0 90)
			(layer "F.Fab")
			(effects
				(font
					(size 1.27 1.27)
				)
			)
		)
		(duplicate_pad_numbers_are_jumpers no)
		(fp_line
			(start 0.7874 -0.4064)
			(end 0.7874 0.4064)
			(stroke
				(width 0.1524)
				(type default)
			)
			(layer "F.SilkS")
		)
		(fp_line
			(start -0.7874 -0.4064)
			(end 0.7874 -0.4064)
			(stroke
				(width 0.1524)
				(type default)
			)
			(layer "F.SilkS")
		)
		(fp_line
			(start 0.7874 0.4064)
			(end -0.7874 0.4064)
			(stroke
				(width 0.1524)
				(type default)
			)
			(layer "F.SilkS")
		)
		(fp_line
			(start -0.7874 0.4064)
			(end -0.7874 -0.4064)
			(stroke
				(width 0.1524)
				(type default)
			)
			(layer "F.SilkS")
		)
		(fp_line
			(start -0.12065 -0.305054)
			(end -0.12065 -0.2794)
			(stroke
				(width 0.1)
				(type default)
			)
			(layer "F.Fab")
		)
		(fp_line
			(start -0.67945 -0.305054)
			(end -0.12065 -0.305054)
			(stroke
				(width 0.1)
				(type default)
			)
			(layer "F.Fab")
		)
		(fp_line
			(start 0.67945 -0.3048)
			(end 0.67945 0.3048)
			(stroke
				(width 0.1)
				(type default)
			)
			(layer "F.Fab")
		)
		(fp_line
			(start 0.12065 -0.3048)
			(end 0.67945 -0.3048)
			(stroke
				(width 0.1)
				(type default)
			)
			(layer "F.Fab")
		)
		(fp_line
			(start 0.12065 -0.2794)
			(end 0.12065 -0.3048)
			(stroke
				(width 0.1)
				(type default)
			)
			(layer "F.Fab")
		)
		(fp_line
			(start -0.12065 -0.2794)
			(end 0.12065 -0.2794)
			(stroke
				(width 0.1)
				(type default)
			)
			(layer "F.Fab")
		)
		(fp_line
			(start 0.120396 0.2794)
			(end -0.12065 0.2794)
			(stroke
				(width 0.1)
				(type default)
			)
			(layer "F.Fab")
		)
		(fp_line
			(start -0.12065 0.2794)
			(end -0.12065 0.3048)
			(stroke
				(width 0.1)
				(type default)
			)
			(layer "F.Fab")
		)
		(fp_line
			(start 0.67945 0.3048)
			(end 0.120396 0.3048)
			(stroke
				(width 0.1)
				(type default)
			)
			(layer "F.Fab")
		)
		(fp_line
			(start 0.120396 0.3048)
			(end 0.120396 0.2794)
			(stroke
				(width 0.1)
				(type default)
			)
			(layer "F.Fab")
		)
		(fp_line
			(start -0.12065 0.3048)
			(end -0.67945 0.3048)
			(stroke
				(width 0.1)
				(type default)
			)
			(layer "F.Fab")
		)
		(fp_line
			(start -0.67945 0.3048)
			(end -0.67945 -0.305054)
			(stroke
				(width 0.1)
				(type default)
			)
			(layer "F.Fab")
		)
		(pad "1" smd circle
			(at -0.40005 0 90)
			(size 0 0)
			(layers "F.Cu" "F.Mask" "F.Paste")
			(net "PU_9ZXL0851_8_15_100M")
		)
		(pad "2" smd circle
			(at 0.40005 0 90)
			(size 0 0)
			(layers "F.Cu" "F.Mask" "F.Paste")
			(net "GND")
		)
	)
	(footprint ""
		(layer "F.Cu")
		(at 361.942634 -379.655324 180)
		(property "Reference" "R6707"
			(at 0 0 180)
			(layer "F.SilkS")
			(hide yes)
			(effects
				(font
					(size 1.27 1.27)
				)
			)
		)
		(property "Value" ""
			(at 0 0 180)
			(layer "F.Fab")
			(effects
				(font
					(size 1.27 1.27)
				)
			)
		)
		(duplicate_pad_numbers_are_jumpers no)
		(fp_line
			(start 0.7874 0.4064)
			(end -0.7874 0.4064)
			(stroke
				(width 0.1524)
				(type default)
			)
			(layer "F.SilkS")
		)
		(fp_line
			(start 0.7874 -0.4064)
			(end 0.7874 0.4064)
			(stroke
				(width 0.1524)
				(type default)
			)
			(layer "F.SilkS")
		)
		(fp_line
			(start -0.7874 0.4064)
			(end -0.7874 -0.4064)
			(stroke
				(width 0.1524)
				(type default)
			)
			(layer "F.SilkS")
		)
		(fp_line
			(start -0.7874 -0.4064)
			(end 0.7874 -0.4064)
			(stroke
				(width 0.1524)
				(type default)
			)
			(layer "F.SilkS")
		)
		(fp_line
			(start 0.67945 0.3048)
			(end 0.120396 0.3048)
			(stroke
				(width 0.1)
				(type default)
			)
			(layer "F.Fab")
		)
		(fp_line
			(start 0.67945 -0.3048)
			(end 0.67945 0.3048)
			(stroke
				(width 0.1)
				(type default)
			)
			(layer "F.Fab")
		)
		(fp_line
			(start 0.12065 -0.2794)
			(end 0.12065 -0.3048)
			(stroke
				(width 0.1)
				(type default)
			)
			(layer "F.Fab")
		)
		(fp_line
			(start 0.12065 -0.3048)
			(end 0.67945 -0.3048)
			(stroke
				(width 0.1)
				(type default)
			)
			(layer "F.Fab")
		)
		(fp_line
			(start 0.120396 0.3048)
			(end 0.120396 0.2794)
			(stroke
				(width 0.1)
				(type default)
			)
			(layer "F.Fab")
		)
		(fp_line
			(start 0.120396 0.2794)
			(end -0.12065 0.2794)
			(stroke
				(width 0.1)
				(type default)
			)
			(layer "F.Fab")
		)
		(fp_line
			(start -0.12065 0.3048)
			(end -0.67945 0.3048)
			(stroke
				(width 0.1)
				(type default)
			)
			(layer "F.Fab")
		)
		(fp_line
			(start -0.12065 0.2794)
			(end -0.12065 0.3048)
			(stroke
				(width 0.1)
				(type default)
			)
			(layer "F.Fab")
		)
		(fp_line
			(start -0.12065 -0.2794)
			(end 0.12065 -0.2794)
			(stroke
				(width 0.1)
				(type default)
			)
			(layer "F.Fab")
		)
		(fp_line
			(start -0.12065 -0.305054)
			(end -0.12065 -0.2794)
			(stroke
				(width 0.1)
				(type default)
			)
			(layer "F.Fab")
		)
		(fp_line
			(start -0.67945 0.3048)
			(end -0.67945 -0.305054)
			(stroke
				(width 0.1)
				(type default)
			)
			(layer "F.Fab")
		)
		(fp_line
			(start -0.67945 -0.305054)
			(end -0.12065 -0.305054)
			(stroke
				(width 0.1)
				(type default)
			)
			(layer "F.Fab")
		)
		(pad "1" smd circle
			(at -0.40005 0 180)
			(size 0 0)
			(layers "F.Cu" "F.Mask" "F.Paste")
			(net "MB_3V3IO_RSVD4_ISO")
		)
		(pad "2" smd circle
			(at 0.40005 0 180)
			(size 0 0)
			(layers "F.Cu" "F.Mask" "F.Paste")
			(net "P3V3_AUX")
		)
	)
	(footprint ""
		(layer "F.Cu")
		(at 80.000602 -350.098614 90)
		(property "Reference" "C109"
			(at 0 0 90)
			(layer "F.SilkS")
			(hide yes)
			(effects
				(font
					(size 1.27 1.27)
				)
			)
		)
		(property "Value" ""
			(at 0 0 90)
			(layer "F.Fab")
			(effects
				(font
					(size 1.27 1.27)
				)
			)
		)
		(duplicate_pad_numbers_are_jumpers no)
		(fp_line
			(start 0.299974 -0.150114)
			(end 0.299974 0.150114)
			(stroke
				(width 0.1)
				(type default)
			)
			(layer "F.Fab")
		)
		(fp_line
			(start -0.299974 -0.150114)
			(end 0.299974 -0.150114)
			(stroke
				(width 0.1)
				(type default)
			)
			(layer "F.Fab")
		)
		(fp_line
			(start 0.299974 0.150114)
			(end -0.299974 0.150114)
			(stroke
				(width 0.1)
				(type default)
			)
			(layer "F.Fab")
		)
		(fp_line
			(start -0.299974 0.150114)
			(end -0.299974 -0.150114)
			(stroke
				(width 0.1)
				(type default)
			)
			(layer "F.Fab")
		)
		(pad "1" smd rect
			(at -0.2667 0 90)
			(size 0.3048 0.381)
			(layers "F.Cu" "F.Mask" "F.Paste")
			(net "P5E_PEX0_STN5_TX_DP<89>")
		)
		(pad "2" smd rect
			(at 0.2667 0 90)
			(size 0.3048 0.381)
			(layers "F.Cu" "F.Mask" "F.Paste")
			(net "P5E_PEX0_STN5_TX_C_DP<89>")
		)
	)
)
